(kicad_pcb
	(version 20260206)
	(generator "pcbnew")
	(generator_version "10.0")
	(general
		(thickness 1.6)
		(legacy_teardrops no)
	)
	(paper "A4")
	(title_block
		(title "04192023_DAF0TMB3IC0_F0TG_MB_C_brd_V02_OCP.brd")
		(comment 1 "Grand Teton / footprints 6662-6667 of 8354")
	)
	(layers
		(0 "F.Cu" signal "TOP")
		(4 "In1.Cu" signal "GND")
		(6 "In2.Cu" signal "IN1")
		(8 "In3.Cu" signal "GND1")
		(10 "In4.Cu" signal "IN2")
		(12 "In5.Cu" signal "GND2")
		(14 "In6.Cu" signal "IN3")
		(16 "In7.Cu" signal "GND3")
		(18 "In8.Cu" signal "VCC")
		(20 "In9.Cu" signal "VCC1")
		(22 "In10.Cu" signal "GND4")
		(24 "In11.Cu" signal "IN4")
		(26 "In12.Cu" signal "GND5")
		(28 "In13.Cu" signal "IN5")
		(30 "In14.Cu" signal "GND6")
		(32 "In15.Cu" signal "IN6")
		(34 "In16.Cu" signal "GND7")
		(2 "B.Cu" signal "BOTTOM")
		(9 "F.Adhes" user "F.Adhesive")
		(11 "B.Adhes" user "B.Adhesive")
		(13 "F.Paste" user "Package Geometry/Pastemask Top")
		(15 "B.Paste" user "Package Geometry/Pastemask Bottom")
		(5 "F.SilkS" user "Ref Des/Silkscreen Top")
		(7 "B.SilkS" user "Ref Des/Silkscreen Bottom")
		(1 "F.Mask" user "Board Geometry/Soldermask Top")
		(3 "B.Mask" user "Board Geometry/Soldermask Bottom")
		(17 "Dwgs.User" user "User.Drawings")
		(19 "Cmts.User" user "User.Comments")
		(21 "Eco1.User" user "User.Eco1")
		(23 "Eco2.User" user "User.Eco2")
		(25 "Edge.Cuts" user "Board Geometry/Outline")
		(27 "Margin" user)
		(31 "F.CrtYd" user "Package Geometry/Place Bound Top")
		(29 "B.CrtYd" user "Package Geometry/Place Bound Bottom")
		(35 "F.Fab" user "Ref Des/Assembly Top")
		(33 "B.Fab" user "Ref Des/Assembly Bottom")
	)
	(footprint ""
		(layer "B.Cu")
		(at 363.804454 -264.35431)
		(property "Reference" "C2138"
			(at 0 0 0)
			(layer "B.SilkS")
			(hide yes)
			(effects
				(font
					(size 1.27 1.27)
				)
				(justify mirror)
			)
		)
		(property "Value" ""
			(at 0 0 0)
			(layer "B.Fab")
			(effects
				(font
					(size 1.27 1.27)
				)
				(justify mirror)
			)
		)
		(duplicate_pad_numbers_are_jumpers no)
		(fp_line
			(start -0.7874 -0.4064)
			(end -0.7874 0.4064)
			(stroke
				(width 0.1524)
				(type default)
			)
			(layer "B.SilkS")
		)
		(fp_line
			(start -0.7874 0.4064)
			(end 0.7874 0.4064)
			(stroke
				(width 0.1524)
				(type default)
			)
			(layer "B.SilkS")
		)
		(fp_line
			(start 0.7874 -0.4064)
			(end -0.7874 -0.4064)
			(stroke
				(width 0.1524)
				(type default)
			)
			(layer "B.SilkS")
		)
		(fp_line
			(start 0.7874 0.4064)
			(end 0.7874 -0.4064)
			(stroke
				(width 0.1524)
				(type default)
			)
			(layer "B.SilkS")
		)
		(fp_line
			(start -0.67945 -0.3048)
			(end -0.67945 0.3048)
			(stroke
				(width 0.1)
				(type default)
			)
			(layer "B.Fab")
		)
		(fp_line
			(start -0.67945 0.3048)
			(end -0.120396 0.3048)
			(stroke
				(width 0.1)
				(type default)
			)
			(layer "B.Fab")
		)
		(fp_line
			(start -0.12065 -0.3048)
			(end -0.67945 -0.3048)
			(stroke
				(width 0.1)
				(type default)
			)
			(layer "B.Fab")
		)
		(fp_line
			(start -0.12065 -0.2794)
			(end -0.12065 -0.3048)
			(stroke
				(width 0.1)
				(type default)
			)
			(layer "B.Fab")
		)
		(fp_line
			(start -0.120396 0.2794)
			(end 0.12065 0.2794)
			(stroke
				(width 0.1)
				(type default)
			)
			(layer "B.Fab")
		)
		(fp_line
			(start -0.120396 0.3048)
			(end -0.120396 0.2794)
			(stroke
				(width 0.1)
				(type default)
			)
			(layer "B.Fab")
		)
		(fp_line
			(start 0.12065 -0.305054)
			(end 0.12065 -0.2794)
			(stroke
				(width 0.1)
				(type default)
			)
			(layer "B.Fab")
		)
		(fp_line
			(start 0.12065 -0.2794)
			(end -0.12065 -0.2794)
			(stroke
				(width 0.1)
				(type default)
			)
			(layer "B.Fab")
		)
		(fp_line
			(start 0.12065 0.2794)
			(end 0.12065 0.3048)
			(stroke
				(width 0.1)
				(type default)
			)
			(layer "B.Fab")
		)
		(fp_line
			(start 0.12065 0.3048)
			(end 0.67945 0.3048)
			(stroke
				(width 0.1)
				(type default)
			)
			(layer "B.Fab")
		)
		(fp_line
			(start 0.67945 -0.305054)
			(end 0.12065 -0.305054)
			(stroke
				(width 0.1)
				(type default)
			)
			(layer "B.Fab")
		)
		(fp_line
			(start 0.67945 0.3048)
			(end 0.67945 -0.305054)
			(stroke
				(width 0.1)
				(type default)
			)
			(layer "B.Fab")
		)
		(pad "1" smd circle
			(at 0.40005 0 180)
			(size 0 0)
			(layers "B.Cu" "B.Mask" "B.Paste")
			(net "PVDD11_S3_P0")
		)
		(pad "2" smd circle
			(at -0.40005 0 180)
			(size 0 0)
			(layers "B.Cu" "B.Mask" "B.Paste")
			(net "GND")
		)
	)
	(footprint ""
		(layer "B.Cu")
		(at 8.19277 -113.161826)
		(property "Reference" "R5238"
			(at 0 0 0)
			(layer "B.SilkS")
			(hide yes)
			(effects
				(font
					(size 1.27 1.27)
				)
				(justify mirror)
			)
		)
		(property "Value" ""
			(at 0 0 0)
			(layer "B.Fab")
			(effects
				(font
					(size 1.27 1.27)
				)
				(justify mirror)
			)
		)
		(duplicate_pad_numbers_are_jumpers no)
		(fp_line
			(start -0.7874 -0.4064)
			(end -0.7874 0.4064)
			(stroke
				(width 0.1524)
				(type default)
			)
			(layer "B.SilkS")
		)
		(fp_line
			(start -0.7874 0.4064)
			(end 0.7874 0.4064)
			(stroke
				(width 0.1524)
				(type default)
			)
			(layer "B.SilkS")
		)
		(fp_line
			(start 0.7874 -0.4064)
			(end -0.7874 -0.4064)
			(stroke
				(width 0.1524)
				(type default)
			)
			(layer "B.SilkS")
		)
		(fp_line
			(start 0.7874 0.4064)
			(end 0.7874 -0.4064)
			(stroke
				(width 0.1524)
				(type default)
			)
			(layer "B.SilkS")
		)
		(fp_line
			(start -0.67945 -0.3048)
			(end -0.67945 0.3048)
			(stroke
				(width 0.1)
				(type default)
			)
			(layer "B.Fab")
		)
		(fp_line
			(start -0.67945 0.3048)
			(end -0.120396 0.3048)
			(stroke
				(width 0.1)
				(type default)
			)
			(layer "B.Fab")
		)
		(fp_line
			(start -0.12065 -0.3048)
			(end -0.67945 -0.3048)
			(stroke
				(width 0.1)
				(type default)
			)
			(layer "B.Fab")
		)
		(fp_line
			(start -0.12065 -0.2794)
			(end -0.12065 -0.3048)
			(stroke
				(width 0.1)
				(type default)
			)
			(layer "B.Fab")
		)
		(fp_line
			(start -0.120396 0.2794)
			(end 0.12065 0.2794)
			(stroke
				(width 0.1)
				(type default)
			)
			(layer "B.Fab")
		)
		(fp_line
			(start -0.120396 0.3048)
			(end -0.120396 0.2794)
			(stroke
				(width 0.1)
				(type default)
			)
			(layer "B.Fab")
		)
		(fp_line
			(start 0.12065 -0.305054)
			(end 0.12065 -0.2794)
			(stroke
				(width 0.1)
				(type default)
			)
			(layer "B.Fab")
		)
		(fp_line
			(start 0.12065 -0.2794)
			(end -0.12065 -0.2794)
			(stroke
				(width 0.1)
				(type default)
			)
			(layer "B.Fab")
		)
		(fp_line
			(start 0.12065 0.2794)
			(end 0.12065 0.3048)
			(stroke
				(width 0.1)
				(type default)
			)
			(layer "B.Fab")
		)
		(fp_line
			(start 0.12065 0.3048)
			(end 0.67945 0.3048)
			(stroke
				(width 0.1)
				(type default)
			)
			(layer "B.Fab")
		)
		(fp_line
			(start 0.67945 -0.305054)
			(end 0.12065 -0.305054)
			(stroke
				(width 0.1)
				(type default)
			)
			(layer "B.Fab")
		)
		(fp_line
			(start 0.67945 0.3048)
			(end 0.67945 -0.305054)
			(stroke
				(width 0.1)
				(type default)
			)
			(layer "B.Fab")
		)
		(pad "1" smd circle
			(at 0.40005 0 180)
			(size 0 0)
			(layers "B.Cu" "B.Mask" "B.Paste")
			(net "PD_U5201_EQ")
		)
		(pad "2" smd circle
			(at -0.40005 0 180)
			(size 0 0)
			(layers "B.Cu" "B.Mask" "B.Paste")
			(net "GND")
		)
	)
	(footprint ""
		(layer "B.Cu")
		(at 175.387 -425.45 90)
		(property "Reference" "U6004"
			(at 4.09067 -0.172974 0)
			(unlocked yes)
			(layer "B.SilkS")
			(effects
				(font
					(size 0.7874 0.5842)
					(thickness 0.1524)
				)
				(justify left mirror)
			)
		)
		(property "Value" ""
			(at 0 0 90)
			(layer "B.Fab")
			(effects
				(font
					(size 1.27 1.27)
				)
				(justify mirror)
			)
		)
		(duplicate_pad_numbers_are_jumpers no)
		(fp_line
			(start 1.603248 -1.500124)
			(end -1.603248 -1.500124)
			(stroke
				(width 0.1524)
				(type default)
			)
			(layer "B.SilkS")
		)
		(fp_line
			(start -1.603248 -1.500124)
			(end -1.603248 1.500124)
			(stroke
				(width 0.1524)
				(type default)
			)
			(layer "B.SilkS")
		)
		(fp_line
			(start 1.603248 1.500124)
			(end 1.603248 -1.500124)
			(stroke
				(width 0.1524)
				(type default)
			)
			(layer "B.SilkS")
		)
		(fp_line
			(start -1.603248 1.500124)
			(end 1.603248 1.500124)
			(stroke
				(width 0.1524)
				(type default)
			)
			(layer "B.SilkS")
		)
		(fp_line
			(start 0.700024 -1.500124)
			(end 0.700024 -1.169924)
			(stroke
				(width 0.1)
				(type default)
			)
			(layer "B.Fab")
		)
		(fp_line
			(start -0.700024 -1.500124)
			(end 0.700024 -1.500124)
			(stroke
				(width 0.1)
				(type default)
			)
			(layer "B.Fab")
		)
		(fp_line
			(start 1.249934 -1.169924)
			(end 1.249934 -0.729996)
			(stroke
				(width 0.1)
				(type default)
			)
			(layer "B.Fab")
		)
		(fp_line
			(start 0.700024 -1.169924)
			(end 1.249934 -1.169924)
			(stroke
				(width 0.1)
				(type default)
			)
			(layer "B.Fab")
		)
		(fp_line
			(start 1.249934 -0.729996)
			(end 0.6985 -0.729996)
			(stroke
				(width 0.1)
				(type default)
			)
			(layer "B.Fab")
		)
		(fp_line
			(start 0.6985 -0.729996)
			(end 0.6985 0.729996)
			(stroke
				(width 0.1)
				(type default)
			)
			(layer "B.Fab")
		)
		(fp_line
			(start -0.700024 -0.219964)
			(end -0.700024 -1.500124)
			(stroke
				(width 0.1)
				(type default)
			)
			(layer "B.Fab")
		)
		(fp_line
			(start -1.249934 -0.219964)
			(end -0.700024 -0.219964)
			(stroke
				(width 0.1)
				(type default)
			)
			(layer "B.Fab")
		)
		(fp_line
			(start -0.700024 0.219964)
			(end -1.249934 0.219964)
			(stroke
				(width 0.1)
				(type default)
			)
			(layer "B.Fab")
		)
		(fp_line
			(start -1.249934 0.219964)
			(end -1.249934 -0.219964)
			(stroke
				(width 0.1)
				(type default)
			)
			(layer "B.Fab")
		)
		(fp_line
			(start 1.249934 0.729996)
			(end 1.249934 1.169924)
			(stroke
				(width 0.1)
				(type default)
			)
			(layer "B.Fab")
		)
		(fp_line
			(start 0.6985 0.729996)
			(end 1.249934 0.729996)
			(stroke
				(width 0.1)
				(type default)
			)
			(layer "B.Fab")
		)
		(fp_line
			(start 1.249934 1.169924)
			(end 0.700024 1.169924)
			(stroke
				(width 0.1)
				(type default)
			)
			(layer "B.Fab")
		)
		(fp_line
			(start 0.700024 1.169924)
			(end 0.700024 1.500124)
			(stroke
				(width 0.1)
				(type default)
			)
			(layer "B.Fab")
		)
		(fp_line
			(start 0.700024 1.500124)
			(end -0.700024 1.500124)
			(stroke
				(width 0.1)
				(type default)
			)
			(layer "B.Fab")
		)
		(fp_line
			(start -0.700024 1.500124)
			(end -0.700024 0.219964)
			(stroke
				(width 0.1)
				(type default)
			)
			(layer "B.Fab")
		)
		(fp_rect
			(start 0.700024 1.500124)
			(end -0.700024 -1.500124)
			(stroke
				(width 0)
				(type default)
			)
			(fill no)
			(layer "B.Fab")
		)
		(pad "D" smd rect
			(at -0.999998 0)
			(size 0.8128 0.9144)
			(layers "B.Cu" "B.Mask" "B.Paste")
			(net "A_HSC_LOW_DRAIN")
		)
		(pad "G" smd rect
			(at 0.999998 -0.94996)
			(size 0.8128 0.9144)
			(layers "B.Cu" "B.Mask" "B.Paste")
			(net "A_HSC_LOW_GATE")
		)
		(pad "S" smd rect
			(at 0.999998 0.94996)
			(size 0.8128 0.9144)
			(layers "B.Cu" "B.Mask" "B.Paste")
			(net "GND")
		)
	)
	(footprint ""
		(layer "B.Cu")
		(at 148.122386 -313.45505 180)
		(property "Reference" "R571"
			(at 0 0 0)
			(layer "B.SilkS")
			(hide yes)
			(effects
				(font
					(size 1.27 1.27)
				)
				(justify mirror)
			)
		)
		(property "Value" ""
			(at 0 0 0)
			(layer "B.Fab")
			(effects
				(font
					(size 1.27 1.27)
				)
				(justify mirror)
			)
		)
		(duplicate_pad_numbers_are_jumpers no)
		(fp_line
			(start 0.7874 0.4064)
			(end 0.7874 -0.4064)
			(stroke
				(width 0.1524)
				(type default)
			)
			(layer "B.SilkS")
		)
		(fp_line
			(start 0.7874 -0.4064)
			(end -0.7874 -0.4064)
			(stroke
				(width 0.1524)
				(type default)
			)
			(layer "B.SilkS")
		)
		(fp_line
			(start -0.7874 0.4064)
			(end 0.7874 0.4064)
			(stroke
				(width 0.1524)
				(type default)
			)
			(layer "B.SilkS")
		)
		(fp_line
			(start -0.7874 -0.4064)
			(end -0.7874 0.4064)
			(stroke
				(width 0.1524)
				(type default)
			)
			(layer "B.SilkS")
		)
		(fp_line
			(start 0.67945 0.3048)
			(end 0.67945 -0.305054)
			(stroke
				(width 0.1)
				(type default)
			)
			(layer "B.Fab")
		)
		(fp_line
			(start 0.67945 -0.305054)
			(end 0.12065 -0.305054)
			(stroke
				(width 0.1)
				(type default)
			)
			(layer "B.Fab")
		)
		(fp_line
			(start 0.12065 0.3048)
			(end 0.67945 0.3048)
			(stroke
				(width 0.1)
				(type default)
			)
			(layer "B.Fab")
		)
		(fp_line
			(start 0.12065 0.2794)
			(end 0.12065 0.3048)
			(stroke
				(width 0.1)
				(type default)
			)
			(layer "B.Fab")
		)
		(fp_line
			(start 0.12065 -0.2794)
			(end -0.12065 -0.2794)
			(stroke
				(width 0.1)
				(type default)
			)
			(layer "B.Fab")
		)
		(fp_line
			(start 0.12065 -0.305054)
			(end 0.12065 -0.2794)
			(stroke
				(width 0.1)
				(type default)
			)
			(layer "B.Fab")
		)
		(fp_line
			(start -0.120396 0.3048)
			(end -0.120396 0.2794)
			(stroke
				(width 0.1)
				(type default)
			)
			(layer "B.Fab")
		)
		(fp_line
			(start -0.120396 0.2794)
			(end 0.12065 0.2794)
			(stroke
				(width 0.1)
				(type default)
			)
			(layer "B.Fab")
		)
		(fp_line
			(start -0.12065 -0.2794)
			(end -0.12065 -0.3048)
			(stroke
				(width 0.1)
				(type default)
			)
			(layer "B.Fab")
		)
		(fp_line
			(start -0.12065 -0.3048)
			(end -0.67945 -0.3048)
			(stroke
				(width 0.1)
				(type default)
			)
			(layer "B.Fab")
		)
		(fp_line
			(start -0.67945 0.3048)
			(end -0.120396 0.3048)
			(stroke
				(width 0.1)
				(type default)
			)
			(layer "B.Fab")
		)
		(fp_line
			(start -0.67945 -0.3048)
			(end -0.67945 0.3048)
			(stroke
				(width 0.1)
				(type default)
			)
			(layer "B.Fab")
		)
		(pad "1" smd circle
			(at 0.40005 0)
			(size 0 0)
			(layers "B.Cu" "B.Mask" "B.Paste")
			(net "XTAL_CPU1_X48M_X1")
		)
		(pad "2" smd circle
			(at -0.40005 0)
			(size 0 0)
			(layers "B.Cu" "B.Mask" "B.Paste")
			(net "XTAL_CPU1_X48M_X2_R")
		)
	)
	(footprint ""
		(layer "B.Cu")
		(at 149.718776 -17.693894 -90)
		(property "Reference" "R2213"
			(at 0 0 90)
			(layer "B.SilkS")
			(hide yes)
			(effects
				(font
					(size 1.27 1.27)
				)
				(justify mirror)
			)
		)
		(property "Value" ""
			(at 0 0 90)
			(layer "B.Fab")
			(effects
				(font
					(size 1.27 1.27)
				)
				(justify mirror)
			)
		)
		(duplicate_pad_numbers_are_jumpers no)
		(fp_line
			(start -0.7874 0.4064)
			(end 0.7874 0.4064)
			(stroke
				(width 0.1524)
				(type default)
			)
			(layer "B.SilkS")
		)
		(fp_line
			(start 0.7874 0.4064)
			(end 0.7874 -0.4064)
			(stroke
				(width 0.1524)
				(type default)
			)
			(layer "B.SilkS")
		)
		(fp_line
			(start -0.7874 -0.4064)
			(end -0.7874 0.4064)
			(stroke
				(width 0.1524)
				(type default)
			)
			(layer "B.SilkS")
		)
		(fp_line
			(start 0.7874 -0.4064)
			(end -0.7874 -0.4064)
			(stroke
				(width 0.1524)
				(type default)
			)
			(layer "B.SilkS")
		)
		(fp_line
			(start -0.67945 0.3048)
			(end -0.120396 0.3048)
			(stroke
				(width 0.1)
				(type default)
			)
			(layer "B.Fab")
		)
		(fp_line
			(start -0.120396 0.3048)
			(end -0.120396 0.2794)
			(stroke
				(width 0.1)
				(type default)
			)
			(layer "B.Fab")
		)
		(fp_line
			(start 0.12065 0.3048)
			(end 0.67945 0.3048)
			(stroke
				(width 0.1)
				(type default)
			)
			(layer "B.Fab")
		)
		(fp_line
			(start 0.67945 0.3048)
			(end 0.67945 -0.305054)
			(stroke
				(width 0.1)
				(type default)
			)
			(layer "B.Fab")
		)
		(fp_line
			(start -0.120396 0.2794)
			(end 0.12065 0.2794)
			(stroke
				(width 0.1)
				(type default)
			)
			(layer "B.Fab")
		)
		(fp_line
			(start 0.12065 0.2794)
			(end 0.12065 0.3048)
			(stroke
				(width 0.1)
				(type default)
			)
			(layer "B.Fab")
		)
		(fp_line
			(start -0.12065 -0.2794)
			(end -0.12065 -0.3048)
			(stroke
				(width 0.1)
				(type default)
			)
			(layer "B.Fab")
		)
		(fp_line
			(start 0.12065 -0.2794)
			(end -0.12065 -0.2794)
			(stroke
				(width 0.1)
				(type default)
			)
			(layer "B.Fab")
		)
		(fp_line
			(start -0.67945 -0.3048)
			(end -0.67945 0.3048)
			(stroke
				(width 0.1)
				(type default)
			)
			(layer "B.Fab")
		)
		(fp_line
			(start -0.12065 -0.3048)
			(end -0.67945 -0.3048)
			(stroke
				(width 0.1)
				(type default)
			)
			(layer "B.Fab")
		)
		(fp_line
			(start 0.12065 -0.305054)
			(end 0.12065 -0.2794)
			(stroke
				(width 0.1)
				(type default)
			)
			(layer "B.Fab")
		)
		(fp_line
			(start 0.67945 -0.305054)
			(end 0.12065 -0.305054)
			(stroke
				(width 0.1)
				(type default)
			)
			(layer "B.Fab")
		)
		(pad "1" smd circle
			(at 0.40005 0 90)
			(size 0 0)
			(layers "B.Cu" "B.Mask" "B.Paste")
			(net "SMB_HOST_CLK_3V3AUX_SDA")
		)
		(pad "2" smd circle
			(at -0.40005 0 90)
			(size 0 0)
			(layers "B.Cu" "B.Mask" "B.Paste")
			(net "P3V3_AUX")
		)
	)
	(footprint ""
		(layer "B.Cu")
		(at 359.416096 -256.012188 -90)
		(property "Reference" "C3925"
			(at 0 0 90)
			(layer "B.SilkS")
			(hide yes)
			(effects
				(font
					(size 1.27 1.27)
				)
				(justify mirror)
			)
		)
		(property "Value" ""
			(at 0 0 90)
			(layer "B.Fab")
			(effects
				(font
					(size 1.27 1.27)
				)
				(justify mirror)
			)
		)
		(duplicate_pad_numbers_are_jumpers no)
		(fp_line
			(start -0.7874 0.4064)
			(end 0.7874 0.4064)
			(stroke
				(width 0.1524)
				(type default)
			)
			(layer "B.SilkS")
		)
		(fp_line
			(start 0.7874 0.4064)
			(end 0.7874 -0.4064)
			(stroke
				(width 0.1524)
				(type default)
			)
			(layer "B.SilkS")
		)
		(fp_line
			(start -0.7874 -0.4064)
			(end -0.7874 0.4064)
			(stroke
				(width 0.1524)
				(type default)
			)
			(layer "B.SilkS")
		)
		(fp_line
			(start 0.7874 -0.4064)
			(end -0.7874 -0.4064)
			(stroke
				(width 0.1524)
				(type default)
			)
			(layer "B.SilkS")
		)
		(fp_line
			(start -0.67945 0.3048)
			(end -0.120396 0.3048)
			(stroke
				(width 0.1)
				(type default)
			)
			(layer "B.Fab")
		)
		(fp_line
			(start -0.120396 0.3048)
			(end -0.120396 0.2794)
			(stroke
				(width 0.1)
				(type default)
			)
			(layer "B.Fab")
		)
		(fp_line
			(start 0.12065 0.3048)
			(end 0.67945 0.3048)
			(stroke
				(width 0.1)
				(type default)
			)
			(layer "B.Fab")
		)
		(fp_line
			(start 0.67945 0.3048)
			(end 0.67945 -0.305054)
			(stroke
				(width 0.1)
				(type default)
			)
			(layer "B.Fab")
		)
		(fp_line
			(start -0.120396 0.2794)
			(end 0.12065 0.2794)
			(stroke
				(width 0.1)
				(type default)
			)
			(layer "B.Fab")
		)
		(fp_line
			(start 0.12065 0.2794)
			(end 0.12065 0.3048)
			(stroke
				(width 0.1)
				(type default)
			)
			(layer "B.Fab")
		)
		(fp_line
			(start -0.12065 -0.2794)
			(end -0.12065 -0.3048)
			(stroke
				(width 0.1)
				(type default)
			)
			(layer "B.Fab")
		)
		(fp_line
			(start 0.12065 -0.2794)
			(end -0.12065 -0.2794)
			(stroke
				(width 0.1)
				(type default)
			)
			(layer "B.Fab")
		)
		(fp_line
			(start -0.67945 -0.3048)
			(end -0.67945 0.3048)
			(stroke
				(width 0.1)
				(type default)
			)
			(layer "B.Fab")
		)
		(fp_line
			(start -0.12065 -0.3048)
			(end -0.67945 -0.3048)
			(stroke
				(width 0.1)
				(type default)
			)
			(layer "B.Fab")
		)
		(fp_line
			(start 0.12065 -0.305054)
			(end 0.12065 -0.2794)
			(stroke
				(width 0.1)
				(type default)
			)
			(layer "B.Fab")
		)
		(fp_line
			(start 0.67945 -0.305054)
			(end 0.12065 -0.305054)
			(stroke
				(width 0.1)
				(type default)
			)
			(layer "B.Fab")
		)
		(pad "1" smd circle
			(at 0.40005 0 90)
			(size 0 0)
			(layers "B.Cu" "B.Mask" "B.Paste")
			(net "PVDDCR_SOC_P0")
		)
		(pad "2" smd circle
			(at -0.40005 0 90)
			(size 0 0)
			(layers "B.Cu" "B.Mask" "B.Paste")
			(net "GND")
		)
	)
)
